# BASEBOARD_FAB2 (Tioga Pass) — schematic netlist excerpt (pin names and nets, part order shuffled) for the footprints in the layout excerpt that follows; sources: Cadence DE-HDL packaged netlist, KiCad conversion of Wiwynn_Tioga_Pass_MB.brd

Q9E1  FET_N_DUAL  NTJD4001N FET  pkg SMLF  page 151
  SOURCE(0)  = GND
  GATE(0)  = FM_BMC_HEARTBEAT_N
  DRAIN(0)  = FM_HEARTBEAT_LED_K
  SOURCE(0)  = GND
  GATE(0)  = FM_HEARTBEAT_LED
  DRAIN(0)  = FM_HEARTBEAT_LED

C9G5  CAP  1.0UF 16V 10% X7S  pkg 0402  page 141 : A = GND_LAN_TRCT1234_C ; B = GND

(kicad_pcb
	(version 20260206)
	(generator "pcbnew")
	(generator_version "10.0")
	(general
		(thickness 1.6)
		(legacy_teardrops no)
	)
	(paper "A4")
	(title_block
		(title "Wiwynn_Tioga_Pass_MB.brd")
		(comment 1 "Tioga Pass / footprints 1185-1186 of 4770")
	)
	(layers
		(0 "F.Cu" signal "TOP")
		(4 "In1.Cu" signal "L2GND")
		(6 "In2.Cu" signal "L3")
		(8 "In3.Cu" signal "L4GND")
		(10 "In4.Cu" signal "L5")
		(12 "In5.Cu" signal "L6GND")
		(14 "In6.Cu" signal "L7VCC")
		(16 "In7.Cu" signal "L8VCC")
		(18 "In8.Cu" signal "L9GND")
		(20 "In9.Cu" signal "L10")
		(22 "In10.Cu" signal "L11GND")
		(24 "In11.Cu" signal "L12")
		(26 "In12.Cu" signal "L13GND")
		(2 "B.Cu" signal "BOTTOM")
		(9 "F.Adhes" user "F.Adhesive")
		(11 "B.Adhes" user "B.Adhesive")
		(13 "F.Paste" user "Package Geometry/Pastemask Top")
		(15 "B.Paste" user "Package Geometry/Pastemask Bottom")
		(5 "F.SilkS" user "Ref Des/Silkscreen Top")
		(7 "B.SilkS" user "Ref Des/Silkscreen Bottom")
		(1 "F.Mask" user "Board Geometry/Soldermask Top")
		(3 "B.Mask" user "Board Geometry/Soldermask Bottom")
		(17 "Dwgs.User" user "User.Drawings")
		(19 "Cmts.User" user "User.Comments")
		(21 "Eco1.User" user "User.Eco1")
		(23 "Eco2.User" user "User.Eco2")
		(25 "Edge.Cuts" user "Board Geometry/Outline")
		(27 "Margin" user)
		(31 "F.CrtYd" user "Package Geometry/Place Bound Top")
		(29 "B.CrtYd" user "Package Geometry/Place Bound Bottom")
		(35 "F.Fab" user "Ref Des/Assembly Top")
		(33 "B.Fab" user "Ref Des/Assembly Bottom")
	)
	(footprint ""
		(layer "F.Cu")
		(at 455.40549 -34.744406 90)
		(property "Reference" "Q9E1"
			(at 3.81 -0.98933 90)
			(unlocked yes)
			(layer "F.SilkS")
			(effects
				(font
					(size 0.7874 0.5842)
					(thickness 0.1524)
				)
				(justify left)
			)
		)
		(property "Value" ""
			(at 0 0 90)
			(layer "F.Fab")
			(effects
				(font
					(size 1.27 1.27)
				)
			)
		)
		(duplicate_pad_numbers_are_jumpers no)
		(fp_circle
			(center -0.844804 -0.416052)
			(end -0.844804 -0.289052)
			(stroke
				(width 0.254)
				(type default)
			)
			(fill no)
			(layer "F.SilkS")
		)
		(fp_poly
			(pts
				(xy 0.2159 1.7526) (xy 1.5621 1.7526) (xy 1.5621 -0.4572) (xy 0.2159 -0.4572)
			)
			(stroke
				(width 0)
				(type default)
			)
			(fill no)
			(layer "F.CrtYd")
		)
		(fp_line
			(start 1.5621 -0.45466)
			(end 0.2159 -0.45466)
			(stroke
				(width 0.1)
				(type default)
			)
			(layer "F.Fab")
		)
		(fp_line
			(start 0.2159 -0.45466)
			(end 0.2159 1.75514)
			(stroke
				(width 0.1)
				(type default)
			)
			(layer "F.Fab")
		)
		(fp_line
			(start 1.5621 1.75514)
			(end 1.5621 -0.45466)
			(stroke
				(width 0.1)
				(type default)
			)
			(layer "F.Fab")
		)
		(fp_line
			(start 0.2159 1.75514)
			(end 1.5621 1.75514)
			(stroke
				(width 0.1)
				(type default)
			)
			(layer "F.Fab")
		)
		(fp_circle
			(center -0.508 -0.7874)
			(end -0.508 -0.6604)
			(stroke
				(width 0.254)
				(type default)
			)
			(fill no)
			(layer "F.Fab")
		)
		(pad "1" smd rect
			(at 0 0 90)
			(size 1.016 0.381)
			(layers "F.Cu" "F.Mask" "F.Paste")
			(net "GND")
		)
		(pad "2" smd rect
			(at 0 0.65024 90)
			(size 1.016 0.381)
			(layers "F.Cu" "F.Mask" "F.Paste")
			(net "FM_BMC_HEARTBEAT_N")
		)
		(pad "3" smd rect
			(at 0 1.30048 90)
			(size 1.016 0.381)
			(layers "F.Cu" "F.Mask" "F.Paste")
			(net "FM_HEARTBEAT_LED_K")
		)
		(pad "4" smd rect
			(at 1.778 1.30048 90)
			(size 1.016 0.381)
			(layers "F.Cu" "F.Mask" "F.Paste")
			(net "GND")
		)
		(pad "5" smd rect
			(at 1.778 0.65024 90)
			(size 1.016 0.381)
			(layers "F.Cu" "F.Mask" "F.Paste")
			(net "FM_HEARTBEAT_LED")
		)
		(pad "6" smd rect
			(at 1.778 0 90)
			(size 1.016 0.381)
			(layers "F.Cu" "F.Mask" "F.Paste")
			(net "FM_HEARTBEAT_LED")
		)
		(zone
			(layer "F.Cu")
			(hatch none 0.5)
			(connect_pads
				(clearance 0)
			)
			(min_thickness 0.25)
			(keepout
				(tracks allowed)
				(vias not_allowed)
				(pads allowed)
				(copperpour not_allowed)
				(footprints allowed)
			)
			(placement
				(enabled no)
				(sheetname "")
			)
			(fill
				(thermal_gap 0.5)
				(thermal_bridge_width 0.5)
				(island_removal_mode 0)
			)
			(polygon
				(pts
					(xy 455.21499 -36.014406) (xy 455.21499 -37.030406) (xy 456.90409 -37.030406) (xy 456.90409 -36.014406)
				)
			)
		)
		(zone
			(layer "F.Cu")
			(hatch none 0.5)
			(connect_pads
				(clearance 0)
			)
			(min_thickness 0.25)
			(keepout
				(tracks allowed)
				(vias not_allowed)
				(pads allowed)
				(copperpour not_allowed)
				(footprints allowed)
			)
			(placement
				(enabled no)
				(sheetname "")
			)
			(fill
				(thermal_gap 0.5)
				(thermal_bridge_width 0.5)
				(island_removal_mode 0)
			)
			(polygon
				(pts
					(xy 455.21499 -34.236406) (xy 455.21499 -35.252406) (xy 456.90409 -35.252406) (xy 456.90409 -34.236406)
				)
			)
		)
	)
	(footprint ""
		(layer "F.Cu")
		(at 479.19386 -18.48739)
		(property "Reference" "C9G5"
			(at 0 0 0)
			(layer "F.SilkS")
			(hide yes)
			(effects
				(font
					(size 1.27 1.27)
				)
			)
		)
		(property "Value" ""
			(at 0 0 0)
			(layer "F.Fab")
			(effects
				(font
					(size 1.27 1.27)
				)
			)
		)
		(duplicate_pad_numbers_are_jumpers no)
		(fp_poly
			(pts
				(xy 0.3048 -0.1016) (xy 0.3048 0.9906) (xy -0.3048 0.9906) (xy -0.3048 -0.1016)
			)
			(stroke
				(width 0)
				(type default)
			)
			(fill no)
			(layer "F.CrtYd")
		)
		(fp_line
			(start -0.3048 -0.1016)
			(end -0.3048 0.9906)
			(stroke
				(width 0.1)
				(type default)
			)
			(layer "F.Fab")
		)
		(fp_line
			(start -0.3048 0.9906)
			(end 0.3048 0.9906)
			(stroke
				(width 0.1)
				(type default)
			)
			(layer "F.Fab")
		)
		(fp_line
			(start 0.3048 -0.1016)
			(end -0.3048 -0.1016)
			(stroke
				(width 0.1)
				(type default)
			)
			(layer "F.Fab")
		)
		(fp_line
			(start 0.3048 0.9906)
			(end 0.3048 -0.1016)
			(stroke
				(width 0.1)
				(type default)
			)
			(layer "F.Fab")
		)
		(pad "1" smd rect
			(at 0 0)
			(size 0.508 0.508)
			(layers "F.Cu" "F.Mask" "F.Paste")
			(net "GND_LAN_TRCT1234_C")
		)
		(pad "2" smd rect
			(at 0 0.889)
			(size 0.508 0.508)
			(layers "F.Cu" "F.Mask" "F.Paste")
			(net "GND")
		)
		(zone
			(layer "F.Cu")
			(hatch none 0.5)
			(connect_pads
				(clearance 0)
			)
			(min_thickness 0.25)
			(keepout
				(tracks allowed)
				(vias not_allowed)
				(pads allowed)
				(copperpour not_allowed)
				(footprints allowed)
			)
			(placement
				(enabled no)
				(sheetname "")
			)
			(fill
				(thermal_gap 0.5)
				(thermal_bridge_width 0.5)
				(island_removal_mode 0)
			)
			(polygon
				(pts
					(xy 478.93986 -18.23339) (xy 479.44786 -18.23339) (xy 479.44786 -17.85239) (xy 478.93986 -17.85239)
				)
			)
		)
		(zone
			(layer "F.Cu")
			(hatch none 0.5)
			(connect_pads
				(clearance 0)
			)
			(min_thickness 0.25)
			(keepout
				(tracks not_allowed)
				(vias allowed)
				(pads allowed)
				(copperpour not_allowed)
				(footprints allowed)
			)
			(placement
				(enabled no)
				(sheetname "")
			)
			(fill
				(thermal_gap 0.5)
				(thermal_bridge_width 0.5)
				(island_removal_mode 0)
			)
			(polygon
				(pts
					(xy 478.93986 -17.85239) (xy 479.44786 -17.85239) (xy 479.44786 -18.23339) (xy 478.93986 -18.23339)
				)
			)
		)
	)
)
